(kicad_pcb
	(version 20241229)
	(generator "pcbnew")
	(generator_version "9.0")
	(general
		(thickness 1.711)
		(legacy_teardrops no)
	)
	(paper "A4")
	(title_block
		(title "Antmicro Baseboard for Jetson AGX Thor")
		(date "2026-02-18")
		(rev "1.1.0")
		(company "Antmicro Ltd")
		(comment 1 "www.antmicro.com")
		(comment 9 "footprints 18-22 of 1170")
	)
	(layers
		(0 "F.Cu" signal)
		(4 "In1.Cu" signal)
		(6 "In2.Cu" signal)
		(8 "In3.Cu" signal)
		(10 "In4.Cu" jumper)
		(12 "In5.Cu" signal)
		(14 "In6.Cu" signal)
		(16 "In7.Cu" signal)
		(18 "In8.Cu" signal)
		(2 "B.Cu" signal)
		(9 "F.Adhes" user "F.Adhesive")
		(11 "B.Adhes" user "B.Adhesive")
		(13 "F.Paste" user)
		(15 "B.Paste" user)
		(5 "F.SilkS" user "F.Silkscreen")
		(7 "B.SilkS" user "B.Silkscreen")
		(1 "F.Mask" user)
		(3 "B.Mask" user)
		(17 "Dwgs.User" user "User.Drawings")
		(19 "Cmts.User" user "User.Comments")
		(21 "Eco1.User" user "User.Eco1")
		(23 "Eco2.User" user "User.Eco2")
		(25 "Edge.Cuts" user)
		(27 "Margin" user)
		(31 "F.CrtYd" user "F.Courtyard")
		(29 "B.CrtYd" user "B.Courtyard")
		(35 "F.Fab" user)
		(33 "B.Fab" user)
	)
	(footprint "antmicro-footprints:C_0402_1005Metric"
		(layer "F.Cu")
		(at 176.63 90.39 -90)
		(descr "Capacitor SMD 0402")
		(tags "capacitor SMD 0402")
		(property "Reference" "C243"
			(at -3.685 0.445 90)
			(layer "F.SilkS")
			(effects
				(font
					(size 0.7 0.7)
					(thickness 0.15)
				)
				(justify right top)
			)
		)
		(property "Value" "C_100n_0402"
			(at -1.022927 2.155213 90)
			(layer "F.Fab")
			(effects
				(font
					(size 0.7 0.7)
					(thickness 0.15)
				)
				(justify right top)
			)
		)
		(property "Datasheet" "https://www.murata.com/products/productdetail?partno=GRM155R61H104KE14%23"
			(at 0 0 90)
			(layer "F.Fab")
			(hide yes)
			(effects
				(font
					(size 1.27 1.27)
					(thickness 0.15)
				)
			)
		)
		(property "Description" "SMD Multilayer Ceramic Capacitor, 0.1 µF, 50 V, 0402 [1005 Metric], ± 10%, X5R, GRM Series"
			(at 0 0 90)
			(layer "F.Fab")
			(hide yes)
			(effects
				(font
					(size 1.27 1.27)
					(thickness 0.15)
				)
			)
		)
		(property "Manufacturer" "Murata"
			(at 0 0 270)
			(unlocked yes)
			(layer "F.Fab")
			(hide yes)
			(effects
				(font
					(size 1 1)
					(thickness 0.15)
				)
			)
		)
		(property "MPN" "GRM155R61H104KE14D"
			(at 0 0 270)
			(unlocked yes)
			(layer "F.Fab")
			(hide yes)
			(effects
				(font
					(size 1 1)
					(thickness 0.15)
				)
			)
		)
		(property "Val" "100n"
			(at 0 0 270)
			(unlocked yes)
			(layer "F.Fab")
			(hide yes)
			(effects
				(font
					(size 1 1)
					(thickness 0.15)
				)
			)
		)
		(property "License" "Apache-2.0"
			(at 0 0 270)
			(unlocked yes)
			(layer "F.Fab")
			(hide yes)
			(effects
				(font
					(size 1 1)
					(thickness 0.15)
				)
			)
		)
		(property "Author" "Antmicro"
			(at 0 0 270)
			(unlocked yes)
			(layer "F.Fab")
			(hide yes)
			(effects
				(font
					(size 1 1)
					(thickness 0.15)
				)
			)
		)
		(property "Voltage" "50V"
			(at 0 0 270)
			(unlocked yes)
			(layer "F.Fab")
			(hide yes)
			(effects
				(font
					(size 1 1)
					(thickness 0.15)
				)
			)
		)
		(property "Dielectric" "X5R"
			(at 0 0 270)
			(unlocked yes)
			(layer "F.Fab")
			(hide yes)
			(effects
				(font
					(size 1 1)
					(thickness 0.15)
				)
			)
		)
		(component_classes
			(class "DCDC_SOM")
		)
		(sheetname "/DCDC/")
		(sheetfile "dcdc.kicad_sch")
		(attr smd)
		(fp_rect
			(start -0.925 -0.47)
			(end 0.925 0.47)
			(stroke
				(width 0.05)
				(type default)
			)
			(fill no)
			(layer "F.CrtYd")
		)
		(fp_line
			(start -0.494 0.248)
			(end -0.494 -0.25)
			(stroke
				(width 0.15)
				(type solid)
			)
			(layer "F.Fab")
		)
		(fp_line
			(start 0.504 0.248)
			(end -0.494 0.248)
			(stroke
				(width 0.15)
				(type solid)
			)
			(layer "F.Fab")
		)
		(fp_line
			(start -0.494 -0.25)
			(end 0.504 -0.25)
			(stroke
				(width 0.15)
				(type solid)
			)
			(layer "F.Fab")
		)
		(fp_line
			(start 0.504 -0.25)
			(end 0.504 0.248)
			(stroke
				(width 0.15)
				(type solid)
			)
			(layer "F.Fab")
		)
		(fp_text user "License: Apache-2.0"
			(at -0.939 5.799 90)
			(layer "F.Fab")
			(effects
				(font
					(size 0.7 0.7)
					(thickness 0.15)
				)
				(justify right top)
			)
		)
		(fp_text user "Author: Antmicro"
			(at -0.939 3.399 90)
			(layer "F.Fab")
			(effects
				(font
					(size 0.7 0.7)
					(thickness 0.15)
				)
				(justify right top)
			)
		)
		(fp_text user "${REFERENCE}"
			(at -0.939 4.599 90)
			(layer "F.Fab")
			(effects
				(font
					(size 0.7 0.7)
					(thickness 0.15)
				)
				(justify right top)
			)
		)
		(pad "1" smd roundrect
			(at -0.48 0 270)
			(size 0.59 0.64)
			(layers "F.Cu" "F.Mask" "F.Paste")
			(roundrect_rratio 0.25)
			(net 13 "VCC")
			(pintype "passive")
		)
		(pad "2" smd roundrect
			(at 0.48 0 270)
			(size 0.59 0.64)
			(layers "F.Cu" "F.Mask" "F.Paste")
			(roundrect_rratio 0.25)
			(net 1 "GND")
			(pintype "passive")
		)
	)
	(footprint "antmicro-footprints:R_0402_1005Metric"
		(layer "F.Cu")
		(at 161.734468 98.145 90)
		(descr "Resistor SMD 0402")
		(tags "resistor SMD 0402")
		(property "Reference" "R370"
			(at -0.955 -1.694468 90)
			(layer "F.SilkS")
			(effects
				(font
					(size 0.7 0.7)
					(thickness 0.15)
				)
				(justify left bottom)
			)
		)
		(property "Value" "R_27R_0402"
			(at -1.011843 1.772047 90)
			(layer "F.Fab")
			(effects
				(font
					(size 0.7 0.7)
					(thickness 0.15)
				)
				(justify left bottom)
			)
		)
		(property "Datasheet" "https://www.bourns.com/docs/product-datasheets/cr.pdf"
			(at 0 0 90)
			(layer "F.Fab")
			(hide yes)
			(effects
				(font
					(size 1.27 1.27)
					(thickness 0.15)
				)
			)
		)
		(property "Description" "SMD Chip Resistor, 27 ohm, ± 1%, 63 mW, 0402 [1005 Metric], Thick Film, General Purpose"
			(at 0 0 90)
			(layer "F.Fab")
			(hide yes)
			(effects
				(font
					(size 1.27 1.27)
					(thickness 0.15)
				)
			)
		)
		(property "Manufacturer" "Bourns"
			(at 0 0 90)
			(unlocked yes)
			(layer "F.Fab")
			(hide yes)
			(effects
				(font
					(size 1 1)
					(thickness 0.15)
				)
			)
		)
		(property "MPN" "CR0402-FX-27R0GLF"
			(at 0 0 90)
			(unlocked yes)
			(layer "F.Fab")
			(hide yes)
			(effects
				(font
					(size 1 1)
					(thickness 0.15)
				)
			)
		)
		(property "Val" "27R"
			(at 0 0 90)
			(unlocked yes)
			(layer "F.Fab")
			(hide yes)
			(effects
				(font
					(size 1 1)
					(thickness 0.15)
				)
			)
		)
		(property "License" "Apache-2.0"
			(at 0 0 90)
			(unlocked yes)
			(layer "F.Fab")
			(hide yes)
			(effects
				(font
					(size 1 1)
					(thickness 0.15)
				)
			)
		)
		(property "Author" "Antmicro"
			(at 0 0 90)
			(unlocked yes)
			(layer "F.Fab")
			(hide yes)
			(effects
				(font
					(size 1 1)
					(thickness 0.15)
				)
			)
		)
		(property "Tolerance" "1%"
			(at 0 0 90)
			(unlocked yes)
			(layer "F.Fab")
			(hide yes)
			(effects
				(font
					(size 1 1)
					(thickness 0.15)
				)
			)
		)
		(component_classes
			(class "DCDC_SOM")
		)
		(sheetname "/DCDC/")
		(sheetfile "dcdc.kicad_sch")
		(attr smd)
		(fp_rect
			(start -0.925 -0.47)
			(end 0.925 0.47)
			(stroke
				(width 0.05)
				(type default)
			)
			(fill no)
			(layer "F.CrtYd")
		)
		(fp_rect
			(start -0.5 -0.25)
			(end 0.5 0.25)
			(stroke
				(width 0.15)
				(type solid)
			)
			(fill no)
			(layer "F.Fab")
		)
		(fp_text user "License: Apache-2.0"
			(at -0.95 5.169 90)
			(layer "F.Fab")
			(effects
				(font
					(size 0.7 0.7)
					(thickness 0.15)
				)
				(justify left bottom)
			)
		)
		(fp_text user "${REFERENCE}"
			(at -0.95 3.168 90)
			(layer "F.Fab")
			(effects
				(font
					(size 0.7 0.7)
					(thickness 0.15)
				)
				(justify left bottom)
			)
		)
		(fp_text user "Author: Antmicro"
			(at -0.95 4.169 90)
			(layer "F.Fab")
			(effects
				(font
					(size 0.7 0.7)
					(thickness 0.15)
				)
				(justify left bottom)
			)
		)
		(pad "1" smd roundrect
			(at -0.48 0 90)
			(size 0.59 0.64)
			(layers "F.Cu" "F.Mask" "F.Paste")
			(roundrect_rratio 0.25)
			(net 1187 "Net-(U22-IN-)")
			(pintype "passive")
		)
		(pad "2" smd roundrect
			(at 0.48 0 90)
			(size 0.59 0.64)
			(layers "F.Cu" "F.Mask" "F.Paste")
			(roundrect_rratio 0.25)
			(net 12 "SYS_VIN_HV")
			(pintype "passive")
		)
	)
	(footprint "antmicro-footprints:R_0402_1005Metric"
		(layer "F.Cu")
		(at 183.2 107.98 180)
		(descr "Resistor SMD 0402")
		(tags "resistor SMD 0402")
		(property "Reference" "R52"
			(at -3.1 0.28 0)
			(layer "F.SilkS")
			(effects
				(font
					(size 0.7 0.7)
					(thickness 0.15)
				)
				(justify right top)
			)
		)
		(property "Value" "R_73k2_0402"
			(at -1.011843 1.772047 0)
			(layer "F.Fab")
			(effects
				(font
					(size 0.7 0.7)
					(thickness 0.15)
				)
				(justify right top)
			)
		)
		(property "Datasheet" "https://www.bourns.com/docs/product-datasheets/cr.pdf"
			(at 0 0 0)
			(layer "F.Fab")
			(hide yes)
			(effects
				(font
					(size 1.27 1.27)
					(thickness 0.15)
				)
			)
		)
		(property "Description" "SMD Chip Resistor"
			(at 0 0 0)
			(layer "F.Fab")
			(hide yes)
			(effects
				(font
					(size 1.27 1.27)
					(thickness 0.15)
				)
			)
		)
		(property "MPN" "CR0402-FX-7322GLF"
			(at 0 0 180)
			(unlocked yes)
			(layer "F.Fab")
			(hide yes)
			(effects
				(font
					(size 1 1)
					(thickness 0.15)
				)
			)
		)
		(property "Manufacturer" "Bourns"
			(at 0 0 180)
			(unlocked yes)
			(layer "F.Fab")
			(hide yes)
			(effects
				(font
					(size 1 1)
					(thickness 0.15)
				)
			)
		)
		(property "License" "Apache-2.0"
			(at 0 0 180)
			(unlocked yes)
			(layer "F.Fab")
			(hide yes)
			(effects
				(font
					(size 1 1)
					(thickness 0.15)
				)
			)
		)
		(property "Author" "Antmicro"
			(at 0 0 180)
			(unlocked yes)
			(layer "F.Fab")
			(hide yes)
			(effects
				(font
					(size 1 1)
					(thickness 0.15)
				)
			)
		)
		(property "Val" "73k2"
			(at 0 0 180)
			(unlocked yes)
			(layer "F.Fab")
			(hide yes)
			(effects
				(font
					(size 1 1)
					(thickness 0.15)
				)
			)
		)
		(property "Tolerance" "1%"
			(at 0 0 180)
			(unlocked yes)
			(layer "F.Fab")
			(hide yes)
			(effects
				(font
					(size 1 1)
					(thickness 0.15)
				)
			)
		)
		(sheetname "/DCDC/")
		(sheetfile "dcdc.kicad_sch")
		(attr smd)
		(fp_rect
			(start -0.925 -0.47)
			(end 0.925 0.47)
			(stroke
				(width 0.05)
				(type default)
			)
			(fill no)
			(layer "F.CrtYd")
		)
		(fp_rect
			(start -0.5 -0.25)
			(end 0.5 0.25)
			(stroke
				(width 0.15)
				(type solid)
			)
			(fill no)
			(layer "F.Fab")
		)
		(fp_text user "License: Apache-2.0"
			(at -0.95 5.169 0)
			(layer "F.Fab")
			(effects
				(font
					(size 0.7 0.7)
					(thickness 0.15)
				)
				(justify right top)
			)
		)
		(fp_text user "Author: Antmicro"
			(at -0.95 4.169 0)
			(layer "F.Fab")
			(effects
				(font
					(size 0.7 0.7)
					(thickness 0.15)
				)
				(justify right top)
			)
		)
		(fp_text user "${REFERENCE}"
			(at -0.95 3.168 0)
			(layer "F.Fab")
			(effects
				(font
					(size 0.7 0.7)
					(thickness 0.15)
				)
				(justify right top)
			)
		)
		(pad "1" smd roundrect
			(at -0.48 0 180)
			(size 0.59 0.64)
			(layers "F.Cu" "F.Mask" "F.Paste")
			(roundrect_rratio 0.25)
			(net 1217 "/DCDC/5V_FB")
			(pintype "passive")
		)
		(pad "2" smd roundrect
			(at 0.48 0 180)
			(size 0.59 0.64)
			(layers "F.Cu" "F.Mask" "F.Paste")
			(roundrect_rratio 0.25)
			(net 253 "/DCDC/5V_OUT")
			(pintype "passive")
		)
	)
	(footprint "antmicro-footprints:C_0402_1005Metric"
		(layer "F.Cu")
		(at 212.4 135.2 -90)
		(descr "Capacitor SMD 0402")
		(tags "capacitor SMD 0402")
		(property "Reference" "C93"
			(at -1 -1.8 90)
			(layer "F.SilkS")
			(effects
				(font
					(size 0.7 0.7)
					(thickness 0.15)
				)
				(justify right top)
			)
		)
		(property "Value" "C_100n_0402"
			(at -1.022927 2.155213 90)
			(layer "F.Fab")
			(effects
				(font
					(size 0.7 0.7)
					(thickness 0.15)
				)
				(justify right top)
			)
		)
		(property "Datasheet" "https://www.murata.com/products/productdetail?partno=GRM155R61H104KE14%23"
			(at 0 0 90)
			(layer "F.Fab")
			(hide yes)
			(effects
				(font
					(size 1.27 1.27)
					(thickness 0.15)
				)
			)
		)
		(property "Description" "SMD Multilayer Ceramic Capacitor, 0.1 µF, 50 V, 0402 [1005 Metric], ± 10%, X5R, GRM Series"
			(at 0 0 90)
			(layer "F.Fab")
			(hide yes)
			(effects
				(font
					(size 1.27 1.27)
					(thickness 0.15)
				)
			)
		)
		(property "MPN" "GRM155R61H104KE14D"
			(at 0 0 270)
			(unlocked yes)
			(layer "F.Fab")
			(hide yes)
			(effects
				(font
					(size 1 1)
					(thickness 0.15)
				)
			)
		)
		(property "Val" "100n"
			(at 0 0 270)
			(unlocked yes)
			(layer "F.Fab")
			(hide yes)
			(effects
				(font
					(size 1 1)
					(thickness 0.15)
				)
			)
		)
		(property "Voltage" "50V"
			(at 0 0 270)
			(unlocked yes)
			(layer "F.Fab")
			(hide yes)
			(effects
				(font
					(size 1 1)
					(thickness 0.15)
				)
			)
		)
		(property "Dielectric" "X5R"
			(at 0 0 270)
			(unlocked yes)
			(layer "F.Fab")
			(hide yes)
			(effects
				(font
					(size 1 1)
					(thickness 0.15)
				)
			)
		)
		(property "Manufacturer" "Murata"
			(at 0 0 270)
			(unlocked yes)
			(layer "F.Fab")
			(hide yes)
			(effects
				(font
					(size 1 1)
					(thickness 0.15)
				)
			)
		)
		(property "License" "Apache-2.0"
			(at 0 0 270)
			(unlocked yes)
			(layer "F.Fab")
			(hide yes)
			(effects
				(font
					(size 1 1)
					(thickness 0.15)
				)
			)
		)
		(property "Author" "Antmicro"
			(at 0 0 270)
			(unlocked yes)
			(layer "F.Fab")
			(hide yes)
			(effects
				(font
					(size 1 1)
					(thickness 0.15)
				)
			)
		)
		(sheetname "/USB Hub/")
		(sheetfile "usb_hub.kicad_sch")
		(attr smd)
		(fp_rect
			(start -0.925 -0.47)
			(end 0.925 0.47)
			(stroke
				(width 0.05)
				(type default)
			)
			(fill no)
			(layer "F.CrtYd")
		)
		(fp_line
			(start -0.494 0.248)
			(end -0.494 -0.25)
			(stroke
				(width 0.15)
				(type solid)
			)
			(layer "F.Fab")
		)
		(fp_line
			(start 0.504 0.248)
			(end -0.494 0.248)
			(stroke
				(width 0.15)
				(type solid)
			)
			(layer "F.Fab")
		)
		(fp_line
			(start -0.494 -0.25)
			(end 0.504 -0.25)
			(stroke
				(width 0.15)
				(type solid)
			)
			(layer "F.Fab")
		)
		(fp_line
			(start 0.504 -0.25)
			(end 0.504 0.248)
			(stroke
				(width 0.15)
				(type solid)
			)
			(layer "F.Fab")
		)
		(fp_text user "${REFERENCE}"
			(at -0.939 4.599 90)
			(layer "F.Fab")
			(effects
				(font
					(size 0.7 0.7)
					(thickness 0.15)
				)
				(justify right top)
			)
		)
		(fp_text user "License: Apache-2.0"
			(at -0.939 5.799 90)
			(layer "F.Fab")
			(effects
				(font
					(size 0.7 0.7)
					(thickness 0.15)
				)
				(justify right top)
			)
		)
		(fp_text user "Author: Antmicro"
			(at -0.939 3.399 90)
			(layer "F.Fab")
			(effects
				(font
					(size 0.7 0.7)
					(thickness 0.15)
				)
				(justify right top)
			)
		)
		(pad "1" smd roundrect
			(at -0.48 0 270)
			(size 0.59 0.64)
			(layers "F.Cu" "F.Mask" "F.Paste")
			(roundrect_rratio 0.25)
			(net 1 "GND")
			(pintype "passive")
		)
		(pad "2" smd roundrect
			(at 0.48 0 270)
			(size 0.59 0.64)
			(layers "F.Cu" "F.Mask" "F.Paste")
			(roundrect_rratio 0.25)
			(net 2 "+3V3")
			(pintype "passive")
		)
	)
	(footprint "antmicro-footprints:C_0805_2012Metric"
		(layer "F.Cu")
		(at 165.91 99.81 90)
		(descr "Capacitor SMD 0805")
		(tags "capacitor SMD 0805")
		(property "Reference" "C299"
			(at -4.595 0.345 90)
			(layer "F.SilkS")
			(effects
				(font
					(size 0.7 0.7)
					(thickness 0.15)
				)
				(justify left bottom)
			)
		)
		(property "Value" "C_22u_25V_0805"
			(at -2.055717 1.963152 90)
			(layer "F.Fab")
			(effects
				(font
					(size 0.7 0.7)
					(thickness 0.15)
				)
				(justify left bottom)
			)
		)
		(property "Datasheet" "https://product.samsungsem.com/mlcc/CL21A226MAYNNN.do"
			(at 0 0 90)
			(layer "F.Fab")
			(hide yes)
			(effects
				(font
					(size 1.27 1.27)
					(thickness 0.15)
				)
			)
		)
		(property "Description" "SMT Multilayer Ceramic Capacitor, 22uF, +/-20%, 25V, X5R, 0805 [2012 Metric]"
			(at 0 0 90)
			(layer "F.Fab")
			(hide yes)
			(effects
				(font
					(size 1.27 1.27)
					(thickness 0.15)
				)
			)
		)
		(property "MPN" "CL21A226MAYNNNE"
			(at 0 0 90)
			(unlocked yes)
			(layer "F.Fab")
			(hide yes)
			(effects
				(font
					(size 1 1)
					(thickness 0.15)
				)
			)
		)
		(property "Manufacturer" "Samsung Electro-Mechanics"
			(at 0 0 90)
			(unlocked yes)
			(layer "F.Fab")
			(hide yes)
			(effects
				(font
					(size 1 1)
					(thickness 0.15)
				)
			)
		)
		(property "License" "Apache-2.0"
			(at 0 0 90)
			(unlocked yes)
			(layer "F.Fab")
			(hide yes)
			(effects
				(font
					(size 1 1)
					(thickness 0.15)
				)
			)
		)
		(property "Author" "Antmicro"
			(at 0 0 90)
			(unlocked yes)
			(layer "F.Fab")
			(hide yes)
			(effects
				(font
					(size 1 1)
					(thickness 0.15)
				)
			)
		)
		(property "Val" "22u"
			(at 0 0 90)
			(unlocked yes)
			(layer "F.Fab")
			(hide yes)
			(effects
				(font
					(size 1 1)
					(thickness 0.15)
				)
			)
		)
		(property "Voltage" "25V"
			(at 0 0 90)
			(unlocked yes)
			(layer "F.Fab")
			(hide yes)
			(effects
				(font
					(size 1 1)
					(thickness 0.15)
				)
			)
		)
		(property "Dielectric" "X5R"
			(at 0 0 90)
			(unlocked yes)
			(layer "F.Fab")
			(hide yes)
			(effects
				(font
					(size 1 1)
					(thickness 0.15)
				)
			)
		)
		(property "Public" "False"
			(at 0 0 90)
			(unlocked yes)
			(layer "F.Fab")
			(hide yes)
			(effects
				(font
					(size 1 1)
					(thickness 0.15)
				)
			)
		)
		(component_classes
			(class "DCDC_SOM")
		)
		(sheetname "/DCDC/")
		(sheetfile "dcdc.kicad_sch")
		(attr smd)
		(fp_line
			(start -0.3 -0.7)
			(end 0.3 -0.7)
			(stroke
				(width 0.15)
				(type solid)
			)
			(layer "F.SilkS")
		)
		(fp_line
			(start -0.3 0.7)
			(end 0.3 0.7)
			(stroke
				(width 0.15)
				(type solid)
			)
			(layer "F.SilkS")
		)
		(fp_rect
			(start 1.95 -0.9)
			(end -1.95 0.9)
			(stroke
				(width 0.05)
				(type default)
			)
			(fill no)
			(layer "F.CrtYd")
		)
		(fp_rect
			(start -0.95 -0.675)
			(end 0.95 0.675)
			(stroke
				(width 0.15)
				(type solid)
			)
			(fill no)
			(layer "F.Fab")
		)
		(fp_text user "${REFERENCE}"
			(at -1.9 3.947 90)
			(layer "F.Fab")
			(effects
				(font
					(size 0.7 0.7)
					(thickness 0.15)
				)
				(justify left bottom)
			)
		)
		(fp_text user "License: Apache-2.0"
			(at -1.9 4.947 90)
			(layer "F.Fab")
			(effects
				(font
					(size 0.7 0.7)
					(thickness 0.15)
				)
				(justify left bottom)
			)
		)
		(fp_text user "Author: Antmicro"
			(at -1.9 5.947 90)
			(layer "F.Fab")
			(effects
				(font
					(size 0.7 0.7)
					(thickness 0.15)
				)
				(justify left bottom)
			)
		)
		(pad "1" smd roundrect
			(at -1.1 0 90)
			(size 1.2 1.3)
			(layers "F.Cu" "F.Mask" "F.Paste")
			(roundrect_rratio 0.25)
			(net 1 "GND")
			(pintype "passive")
		)
		(pad "2" smd roundrect
			(at 1.1 0 90)
			(size 1.2 1.3)
			(layers "F.Cu" "F.Mask" "F.Paste")
			(roundrect_rratio 0.25)
			(net 903 "/DCDC/16V_OUT")
			(pintype "passive")
		)
	)
)
